(kicad_pcb
	(version 20260206)
	(generator "pcbnew")
	(generator_version "10.0")
	(general
		(thickness 1.6)
		(legacy_teardrops no)
	)
	(paper "A4")
	(title_block
		(title "01162023_DA0F0TEBIF0_F0T_Expander_BD_F_brd_V02_OCP.brd")
		(comment 1 "Grand Teton / footprints 506-511 of 9728")
	)
	(layers
		(0 "F.Cu" signal "TOP")
		(4 "In1.Cu" signal "GND")
		(6 "In2.Cu" signal "VCC")
		(8 "In3.Cu" signal "VCC1")
		(10 "In4.Cu" signal "GND1")
		(12 "In5.Cu" signal "IN1")
		(14 "In6.Cu" signal "GND2")
		(16 "In7.Cu" signal "IN2")
		(18 "In8.Cu" signal "GND3")
		(20 "In9.Cu" signal "IN3")
		(22 "In10.Cu" signal "GND4")
		(24 "In11.Cu" signal "IN4")
		(26 "In12.Cu" signal "GND5")
		(28 "In13.Cu" signal "IN5")
		(30 "In14.Cu" signal "GND6")
		(32 "In15.Cu" signal "IN6")
		(34 "In16.Cu" signal "GND7")
		(2 "B.Cu" signal "BOTTOM")
		(9 "F.Adhes" user "F.Adhesive")
		(11 "B.Adhes" user "B.Adhesive")
		(13 "F.Paste" user "Package Geometry/Pastemask Top")
		(15 "B.Paste" user "Package Geometry/Pastemask Bottom")
		(5 "F.SilkS" user "Ref Des/Silkscreen Top")
		(7 "B.SilkS" user "Ref Des/Silkscreen Bottom")
		(1 "F.Mask" user "Board Geometry/Soldermask Top")
		(3 "B.Mask" user "Board Geometry/Soldermask Bottom")
		(17 "Dwgs.User" user "User.Drawings")
		(19 "Cmts.User" user "User.Comments")
		(21 "Eco1.User" user "User.Eco1")
		(23 "Eco2.User" user "User.Eco2")
		(25 "Edge.Cuts" user "Board Geometry/Outline")
		(27 "Margin" user)
		(31 "F.CrtYd" user "Package Geometry/Place Bound Top")
		(29 "B.CrtYd" user "Package Geometry/Place Bound Bottom")
		(35 "F.Fab" user "Ref Des/Assembly Top")
		(33 "B.Fab" user "Ref Des/Assembly Bottom")
	)
	(footprint ""
		(layer "F.Cu")
		(at 349.31731 -260.671564 90)
		(property "Reference" "PC130"
			(at 0 0 90)
			(layer "F.SilkS")
			(hide yes)
			(effects
				(font
					(size 1.27 1.27)
				)
			)
		)
		(property "Value" ""
			(at 0 0 90)
			(layer "F.Fab")
			(effects
				(font
					(size 1.27 1.27)
				)
			)
		)
		(duplicate_pad_numbers_are_jumpers no)
		(fp_line
			(start 0.7874 -0.4064)
			(end 0.7874 0.4064)
			(stroke
				(width 0.1524)
				(type default)
			)
			(layer "F.SilkS")
		)
		(fp_line
			(start -0.7874 -0.4064)
			(end 0.7874 -0.4064)
			(stroke
				(width 0.1524)
				(type default)
			)
			(layer "F.SilkS")
		)
		(fp_line
			(start 0.7874 0.4064)
			(end -0.7874 0.4064)
			(stroke
				(width 0.1524)
				(type default)
			)
			(layer "F.SilkS")
		)
		(fp_line
			(start -0.7874 0.4064)
			(end -0.7874 -0.4064)
			(stroke
				(width 0.1524)
				(type default)
			)
			(layer "F.SilkS")
		)
		(fp_line
			(start -0.12065 -0.305054)
			(end -0.12065 -0.2794)
			(stroke
				(width 0.1)
				(type default)
			)
			(layer "F.Fab")
		)
		(fp_line
			(start -0.67945 -0.305054)
			(end -0.12065 -0.305054)
			(stroke
				(width 0.1)
				(type default)
			)
			(layer "F.Fab")
		)
		(fp_line
			(start 0.67945 -0.3048)
			(end 0.67945 0.3048)
			(stroke
				(width 0.1)
				(type default)
			)
			(layer "F.Fab")
		)
		(fp_line
			(start 0.12065 -0.3048)
			(end 0.67945 -0.3048)
			(stroke
				(width 0.1)
				(type default)
			)
			(layer "F.Fab")
		)
		(fp_line
			(start 0.12065 -0.2794)
			(end 0.12065 -0.3048)
			(stroke
				(width 0.1)
				(type default)
			)
			(layer "F.Fab")
		)
		(fp_line
			(start -0.12065 -0.2794)
			(end 0.12065 -0.2794)
			(stroke
				(width 0.1)
				(type default)
			)
			(layer "F.Fab")
		)
		(fp_line
			(start 0.120396 0.2794)
			(end -0.12065 0.2794)
			(stroke
				(width 0.1)
				(type default)
			)
			(layer "F.Fab")
		)
		(fp_line
			(start -0.12065 0.2794)
			(end -0.12065 0.3048)
			(stroke
				(width 0.1)
				(type default)
			)
			(layer "F.Fab")
		)
		(fp_line
			(start 0.67945 0.3048)
			(end 0.120396 0.3048)
			(stroke
				(width 0.1)
				(type default)
			)
			(layer "F.Fab")
		)
		(fp_line
			(start 0.120396 0.3048)
			(end 0.120396 0.2794)
			(stroke
				(width 0.1)
				(type default)
			)
			(layer "F.Fab")
		)
		(fp_line
			(start -0.12065 0.3048)
			(end -0.67945 0.3048)
			(stroke
				(width 0.1)
				(type default)
			)
			(layer "F.Fab")
		)
		(fp_line
			(start -0.67945 0.3048)
			(end -0.67945 -0.305054)
			(stroke
				(width 0.1)
				(type default)
			)
			(layer "F.Fab")
		)
		(pad "1" smd circle
			(at -0.40005 0 90)
			(size 0 0)
			(layers "F.Cu" "F.Mask" "F.Paste")
			(net "P0V8_PEX3_VSEN3")
		)
		(pad "2" smd circle
			(at 0.40005 0 90)
			(size 0 0)
			(layers "F.Cu" "F.Mask" "F.Paste")
			(net "SH_P0V8_PEX3_RGND3")
		)
	)
	(footprint ""
		(layer "F.Cu")
		(at 421.589962 -72.766682 90)
		(property "Reference" "PR7094"
			(at 0 0 90)
			(layer "F.SilkS")
			(hide yes)
			(effects
				(font
					(size 1.27 1.27)
				)
			)
		)
		(property "Value" ""
			(at 0 0 90)
			(layer "F.Fab")
			(effects
				(font
					(size 1.27 1.27)
				)
			)
		)
		(duplicate_pad_numbers_are_jumpers no)
		(fp_line
			(start 0.7874 -0.4064)
			(end 0.7874 0.4064)
			(stroke
				(width 0.1524)
				(type default)
			)
			(layer "F.SilkS")
		)
		(fp_line
			(start -0.7874 -0.4064)
			(end 0.7874 -0.4064)
			(stroke
				(width 0.1524)
				(type default)
			)
			(layer "F.SilkS")
		)
		(fp_line
			(start 0.7874 0.4064)
			(end -0.7874 0.4064)
			(stroke
				(width 0.1524)
				(type default)
			)
			(layer "F.SilkS")
		)
		(fp_line
			(start -0.7874 0.4064)
			(end -0.7874 -0.4064)
			(stroke
				(width 0.1524)
				(type default)
			)
			(layer "F.SilkS")
		)
		(fp_line
			(start -0.12065 -0.305054)
			(end -0.12065 -0.2794)
			(stroke
				(width 0.1)
				(type default)
			)
			(layer "F.Fab")
		)
		(fp_line
			(start -0.67945 -0.305054)
			(end -0.12065 -0.305054)
			(stroke
				(width 0.1)
				(type default)
			)
			(layer "F.Fab")
		)
		(fp_line
			(start 0.67945 -0.3048)
			(end 0.67945 0.3048)
			(stroke
				(width 0.1)
				(type default)
			)
			(layer "F.Fab")
		)
		(fp_line
			(start 0.12065 -0.3048)
			(end 0.67945 -0.3048)
			(stroke
				(width 0.1)
				(type default)
			)
			(layer "F.Fab")
		)
		(fp_line
			(start 0.12065 -0.2794)
			(end 0.12065 -0.3048)
			(stroke
				(width 0.1)
				(type default)
			)
			(layer "F.Fab")
		)
		(fp_line
			(start -0.12065 -0.2794)
			(end 0.12065 -0.2794)
			(stroke
				(width 0.1)
				(type default)
			)
			(layer "F.Fab")
		)
		(fp_line
			(start 0.120396 0.2794)
			(end -0.12065 0.2794)
			(stroke
				(width 0.1)
				(type default)
			)
			(layer "F.Fab")
		)
		(fp_line
			(start -0.12065 0.2794)
			(end -0.12065 0.3048)
			(stroke
				(width 0.1)
				(type default)
			)
			(layer "F.Fab")
		)
		(fp_line
			(start 0.67945 0.3048)
			(end 0.120396 0.3048)
			(stroke
				(width 0.1)
				(type default)
			)
			(layer "F.Fab")
		)
		(fp_line
			(start 0.120396 0.3048)
			(end 0.120396 0.2794)
			(stroke
				(width 0.1)
				(type default)
			)
			(layer "F.Fab")
		)
		(fp_line
			(start -0.12065 0.3048)
			(end -0.67945 0.3048)
			(stroke
				(width 0.1)
				(type default)
			)
			(layer "F.Fab")
		)
		(fp_line
			(start -0.67945 0.3048)
			(end -0.67945 -0.305054)
			(stroke
				(width 0.1)
				(type default)
			)
			(layer "F.Fab")
		)
		(pad "1" smd circle
			(at -0.40005 0 90)
			(size 0 0)
			(layers "F.Cu" "F.Mask" "F.Paste")
			(net "P12V_SSD14_CO_ILIMIT")
		)
		(pad "2" smd circle
			(at 0.40005 0 90)
			(size 0 0)
			(layers "F.Cu" "F.Mask" "F.Paste")
			(net "GND")
		)
	)
	(footprint ""
		(layer "F.Cu")
		(at 324.083934 -289.230816 90)
		(property "Reference" "R3982"
			(at 0 0 90)
			(layer "F.SilkS")
			(hide yes)
			(effects
				(font
					(size 1.27 1.27)
				)
			)
		)
		(property "Value" ""
			(at 0 0 90)
			(layer "F.Fab")
			(effects
				(font
					(size 1.27 1.27)
				)
			)
		)
		(duplicate_pad_numbers_are_jumpers no)
		(fp_line
			(start 0.7874 -0.4064)
			(end 0.7874 0.4064)
			(stroke
				(width 0.1524)
				(type default)
			)
			(layer "F.SilkS")
		)
		(fp_line
			(start -0.7874 -0.4064)
			(end 0.7874 -0.4064)
			(stroke
				(width 0.1524)
				(type default)
			)
			(layer "F.SilkS")
		)
		(fp_line
			(start 0.7874 0.4064)
			(end -0.7874 0.4064)
			(stroke
				(width 0.1524)
				(type default)
			)
			(layer "F.SilkS")
		)
		(fp_line
			(start -0.7874 0.4064)
			(end -0.7874 -0.4064)
			(stroke
				(width 0.1524)
				(type default)
			)
			(layer "F.SilkS")
		)
		(fp_line
			(start -0.12065 -0.305054)
			(end -0.12065 -0.2794)
			(stroke
				(width 0.1)
				(type default)
			)
			(layer "F.Fab")
		)
		(fp_line
			(start -0.67945 -0.305054)
			(end -0.12065 -0.305054)
			(stroke
				(width 0.1)
				(type default)
			)
			(layer "F.Fab")
		)
		(fp_line
			(start 0.67945 -0.3048)
			(end 0.67945 0.3048)
			(stroke
				(width 0.1)
				(type default)
			)
			(layer "F.Fab")
		)
		(fp_line
			(start 0.12065 -0.3048)
			(end 0.67945 -0.3048)
			(stroke
				(width 0.1)
				(type default)
			)
			(layer "F.Fab")
		)
		(fp_line
			(start 0.12065 -0.2794)
			(end 0.12065 -0.3048)
			(stroke
				(width 0.1)
				(type default)
			)
			(layer "F.Fab")
		)
		(fp_line
			(start -0.12065 -0.2794)
			(end 0.12065 -0.2794)
			(stroke
				(width 0.1)
				(type default)
			)
			(layer "F.Fab")
		)
		(fp_line
			(start 0.120396 0.2794)
			(end -0.12065 0.2794)
			(stroke
				(width 0.1)
				(type default)
			)
			(layer "F.Fab")
		)
		(fp_line
			(start -0.12065 0.2794)
			(end -0.12065 0.3048)
			(stroke
				(width 0.1)
				(type default)
			)
			(layer "F.Fab")
		)
		(fp_line
			(start 0.67945 0.3048)
			(end 0.120396 0.3048)
			(stroke
				(width 0.1)
				(type default)
			)
			(layer "F.Fab")
		)
		(fp_line
			(start 0.120396 0.3048)
			(end 0.120396 0.2794)
			(stroke
				(width 0.1)
				(type default)
			)
			(layer "F.Fab")
		)
		(fp_line
			(start -0.12065 0.3048)
			(end -0.67945 0.3048)
			(stroke
				(width 0.1)
				(type default)
			)
			(layer "F.Fab")
		)
		(fp_line
			(start -0.67945 0.3048)
			(end -0.67945 -0.305054)
			(stroke
				(width 0.1)
				(type default)
			)
			(layer "F.Fab")
		)
		(pad "1" smd circle
			(at -0.40005 0 90)
			(size 0 0)
			(layers "F.Cu" "F.Mask" "F.Paste")
			(net "SMB_PEX2_PCA9555_SCL")
		)
		(pad "2" smd circle
			(at 0.40005 0 90)
			(size 0 0)
			(layers "F.Cu" "F.Mask" "F.Paste")
			(net "SMB_PEX2_HOST_LS_SCL")
		)
	)
	(footprint ""
		(layer "F.Cu")
		(at 232.409746 -119.797068 180)
		(property "Reference" "PR6898"
			(at 0 0 180)
			(layer "F.SilkS")
			(hide yes)
			(effects
				(font
					(size 1.27 1.27)
				)
			)
		)
		(property "Value" ""
			(at 0 0 180)
			(layer "F.Fab")
			(effects
				(font
					(size 1.27 1.27)
				)
			)
		)
		(duplicate_pad_numbers_are_jumpers no)
		(fp_line
			(start 0.7874 0.4064)
			(end -0.7874 0.4064)
			(stroke
				(width 0.1524)
				(type default)
			)
			(layer "F.SilkS")
		)
		(fp_line
			(start 0.7874 -0.4064)
			(end 0.7874 0.4064)
			(stroke
				(width 0.1524)
				(type default)
			)
			(layer "F.SilkS")
		)
		(fp_line
			(start -0.7874 0.4064)
			(end -0.7874 -0.4064)
			(stroke
				(width 0.1524)
				(type default)
			)
			(layer "F.SilkS")
		)
		(fp_line
			(start -0.7874 -0.4064)
			(end 0.7874 -0.4064)
			(stroke
				(width 0.1524)
				(type default)
			)
			(layer "F.SilkS")
		)
		(fp_line
			(start 0.67945 0.3048)
			(end 0.120396 0.3048)
			(stroke
				(width 0.1)
				(type default)
			)
			(layer "F.Fab")
		)
		(fp_line
			(start 0.67945 -0.3048)
			(end 0.67945 0.3048)
			(stroke
				(width 0.1)
				(type default)
			)
			(layer "F.Fab")
		)
		(fp_line
			(start 0.12065 -0.2794)
			(end 0.12065 -0.3048)
			(stroke
				(width 0.1)
				(type default)
			)
			(layer "F.Fab")
		)
		(fp_line
			(start 0.12065 -0.3048)
			(end 0.67945 -0.3048)
			(stroke
				(width 0.1)
				(type default)
			)
			(layer "F.Fab")
		)
		(fp_line
			(start 0.120396 0.3048)
			(end 0.120396 0.2794)
			(stroke
				(width 0.1)
				(type default)
			)
			(layer "F.Fab")
		)
		(fp_line
			(start 0.120396 0.2794)
			(end -0.12065 0.2794)
			(stroke
				(width 0.1)
				(type default)
			)
			(layer "F.Fab")
		)
		(fp_line
			(start -0.12065 0.3048)
			(end -0.67945 0.3048)
			(stroke
				(width 0.1)
				(type default)
			)
			(layer "F.Fab")
		)
		(fp_line
			(start -0.12065 0.2794)
			(end -0.12065 0.3048)
			(stroke
				(width 0.1)
				(type default)
			)
			(layer "F.Fab")
		)
		(fp_line
			(start -0.12065 -0.2794)
			(end 0.12065 -0.2794)
			(stroke
				(width 0.1)
				(type default)
			)
			(layer "F.Fab")
		)
		(fp_line
			(start -0.12065 -0.305054)
			(end -0.12065 -0.2794)
			(stroke
				(width 0.1)
				(type default)
			)
			(layer "F.Fab")
		)
		(fp_line
			(start -0.67945 0.3048)
			(end -0.67945 -0.305054)
			(stroke
				(width 0.1)
				(type default)
			)
			(layer "F.Fab")
		)
		(fp_line
			(start -0.67945 -0.305054)
			(end -0.12065 -0.305054)
			(stroke
				(width 0.1)
				(type default)
			)
			(layer "F.Fab")
		)
		(pad "1" smd circle
			(at -0.40005 0 180)
			(size 0 0)
			(layers "F.Cu" "F.Mask" "F.Paste")
			(net "P12V_NIC3_CO_OV_FB")
		)
		(pad "2" smd circle
			(at 0.40005 0 180)
			(size 0 0)
			(layers "F.Cu" "F.Mask" "F.Paste")
			(net "GND")
		)
	)
	(footprint ""
		(layer "F.Cu")
		(at 320.354452 -224.659698 180)
		(property "Reference" "D14"
			(at 3.743452 0.103632 0)
			(unlocked yes)
			(layer "F.SilkS")
			(effects
				(font
					(size 0.7874 0.5842)
					(thickness 0.1524)
				)
				(justify left)
			)
		)
		(property "Value" ""
			(at 0 0 180)
			(layer "F.Fab")
			(effects
				(font
					(size 1.27 1.27)
				)
			)
		)
		(duplicate_pad_numbers_are_jumpers no)
		(fp_line
			(start 1.16078 0.4826)
			(end -0.64008 0.4826)
			(stroke
				(width 0.1524)
				(type default)
			)
			(layer "F.SilkS")
		)
		(fp_line
			(start 1.16078 -0.4826)
			(end 1.16078 0.4826)
			(stroke
				(width 0.1524)
				(type default)
			)
			(layer "F.SilkS")
		)
		(fp_line
			(start 1.03378 0.4826)
			(end -0.79248 0.4826)
			(stroke
				(width 0.1524)
				(type default)
			)
			(layer "F.SilkS")
		)
		(fp_line
			(start 1.03378 -0.4826)
			(end 1.03378 0.4826)
			(stroke
				(width 0.1524)
				(type default)
			)
			(layer "F.SilkS")
		)
		(fp_line
			(start 0.90678 0.4826)
			(end -0.90678 0.4826)
			(stroke
				(width 0.1524)
				(type default)
			)
			(layer "F.SilkS")
		)
		(fp_line
			(start 0.90678 -0.4826)
			(end 0.90678 0.4826)
			(stroke
				(width 0.1524)
				(type default)
			)
			(layer "F.SilkS")
		)
		(fp_line
			(start -0.64008 -0.4826)
			(end 1.16078 -0.4826)
			(stroke
				(width 0.1524)
				(type default)
			)
			(layer "F.SilkS")
		)
		(fp_line
			(start -0.79248 -0.4826)
			(end 1.03378 -0.4826)
			(stroke
				(width 0.1524)
				(type default)
			)
			(layer "F.SilkS")
		)
		(fp_line
			(start -0.89408 -0.4826)
			(end 0.90678 -0.4826)
			(stroke
				(width 0.1524)
				(type default)
			)
			(layer "F.SilkS")
		)
		(fp_line
			(start -0.90678 0.4826)
			(end -0.90678 -0.4699)
			(stroke
				(width 0.1524)
				(type default)
			)
			(layer "F.SilkS")
		)
		(fp_line
			(start 0.499872 0.249936)
			(end -0.499872 0.249936)
			(stroke
				(width 0.1)
				(type default)
			)
			(layer "F.Fab")
		)
		(fp_line
			(start 0.499872 -0.249936)
			(end 0.499872 0.249936)
			(stroke
				(width 0.1)
				(type default)
			)
			(layer "F.Fab")
		)
		(fp_line
			(start -0.499872 0.249936)
			(end -0.499872 -0.249936)
			(stroke
				(width 0.1)
				(type default)
			)
			(layer "F.Fab")
		)
		(fp_line
			(start -0.499872 -0.249936)
			(end 0.499872 -0.249936)
			(stroke
				(width 0.1)
				(type default)
			)
			(layer "F.Fab")
		)
		(pad "A" smd rect
			(at -0.47498 0 180)
			(size 0.6096 0.7112)
			(layers "F.Cu" "F.Mask" "F.Paste")
			(net "LED_POSTCODE_R_1")
		)
		(pad "C" smd rect
			(at 0.47498 0 180)
			(size 0.6096 0.7112)
			(layers "F.Cu" "F.Mask" "F.Paste")
			(net "FPGA_DEBUG_LED_R_N")
		)
	)
	(footprint ""
		(layer "F.Cu")
		(at 243.8273 -185.429652 -90)
		(property "Reference" "R3152"
			(at 0 0 270)
			(layer "F.SilkS")
			(hide yes)
			(effects
				(font
					(size 1.27 1.27)
				)
			)
		)
		(property "Value" ""
			(at 0 0 270)
			(layer "F.Fab")
			(effects
				(font
					(size 1.27 1.27)
				)
			)
		)
		(duplicate_pad_numbers_are_jumpers no)
		(fp_line
			(start -0.7874 0.4064)
			(end -0.7874 -0.4064)
			(stroke
				(width 0.1524)
				(type default)
			)
			(layer "F.SilkS")
		)
		(fp_line
			(start 0.7874 0.4064)
			(end -0.7874 0.4064)
			(stroke
				(width 0.1524)
				(type default)
			)
			(layer "F.SilkS")
		)
		(fp_line
			(start -0.7874 -0.4064)
			(end 0.7874 -0.4064)
			(stroke
				(width 0.1524)
				(type default)
			)
			(layer "F.SilkS")
		)
		(fp_line
			(start 0.7874 -0.4064)
			(end 0.7874 0.4064)
			(stroke
				(width 0.1524)
				(type default)
			)
			(layer "F.SilkS")
		)
		(fp_line
			(start -0.67945 0.3048)
			(end -0.67945 -0.305054)
			(stroke
				(width 0.1)
				(type default)
			)
			(layer "F.Fab")
		)
		(fp_line
			(start -0.12065 0.3048)
			(end -0.67945 0.3048)
			(stroke
				(width 0.1)
				(type default)
			)
			(layer "F.Fab")
		)
		(fp_line
			(start 0.120396 0.3048)
			(end 0.120396 0.2794)
			(stroke
				(width 0.1)
				(type default)
			)
			(layer "F.Fab")
		)
		(fp_line
			(start 0.67945 0.3048)
			(end 0.120396 0.3048)
			(stroke
				(width 0.1)
				(type default)
			)
			(layer "F.Fab")
		)
		(fp_line
			(start -0.12065 0.2794)
			(end -0.12065 0.3048)
			(stroke
				(width 0.1)
				(type default)
			)
			(layer "F.Fab")
		)
		(fp_line
			(start 0.120396 0.2794)
			(end -0.12065 0.2794)
			(stroke
				(width 0.1)
				(type default)
			)
			(layer "F.Fab")
		)
		(fp_line
			(start -0.12065 -0.2794)
			(end 0.12065 -0.2794)
			(stroke
				(width 0.1)
				(type default)
			)
			(layer "F.Fab")
		)
		(fp_line
			(start 0.12065 -0.2794)
			(end 0.12065 -0.3048)
			(stroke
				(width 0.1)
				(type default)
			)
			(layer "F.Fab")
		)
		(fp_line
			(start 0.12065 -0.3048)
			(end 0.67945 -0.3048)
			(stroke
				(width 0.1)
				(type default)
			)
			(layer "F.Fab")
		)
		(fp_line
			(start 0.67945 -0.3048)
			(end 0.67945 0.3048)
			(stroke
				(width 0.1)
				(type default)
			)
			(layer "F.Fab")
		)
		(fp_line
			(start -0.67945 -0.305054)
			(end -0.12065 -0.305054)
			(stroke
				(width 0.1)
				(type default)
			)
			(layer "F.Fab")
		)
		(fp_line
			(start -0.12065 -0.305054)
			(end -0.12065 -0.2794)
			(stroke
				(width 0.1)
				(type default)
			)
			(layer "F.Fab")
		)
		(pad "1" smd circle
			(at -0.40005 0 270)
			(size 0 0)
			(layers "F.Cu" "F.Mask" "F.Paste")
			(net "PWRGD_P1V2_AUX_FPGA_R")
		)
		(pad "2" smd circle
			(at 0.40005 0 270)
			(size 0 0)
			(layers "F.Cu" "F.Mask" "F.Paste")
			(net "PWRGD_P1V2_AUX_RST")
		)
	)
)
